# TIMECARD (Time Appliance Project (Time Card)) — schematic netlist excerpt (pin names and nets, part order shuffled) for the footprints in the layout excerpt that follows; sources: Cadence DE-HDL packaged netlist, KiCad conversion of R4006-B0001-02_R01.brd

P3  CONN_HDR_2X3_M_RA_TH  pkg P_M_H_2X3_NP2_RA_P165_V1  page 27
  \1\  = XP12R0V_EXT
  \2\  = XP12R0V_EXT
  \3\  = XP12R0V_EXT
  \4\  = SG
  \5\  = SG
  \6\  = SG

(kicad_pcb
	(version 20260206)
	(generator "pcbnew")
	(generator_version "10.0")
	(general
		(thickness 1.6)
		(legacy_teardrops no)
	)
	(paper "A4")
	(title_block
		(title "timecard-production-celestica-r4006 — R4006-B0001-02_R01.brd")
		(comment 1 "Time Appliance Project (Time Card) / footprints 56-56 of 1113")
	)
	(layers
		(0 "F.Cu" signal "TOP")
		(4 "In1.Cu" signal "L02_GND1")
		(6 "In2.Cu" signal "L03_SIG1")
		(8 "In3.Cu" signal "L04_GND2")
		(10 "In4.Cu" signal "L05_VCC1")
		(12 "In5.Cu" signal "L06_VCC2")
		(14 "In6.Cu" signal "L07_GND3")
		(16 "In7.Cu" signal "L08_SIG2")
		(18 "In8.Cu" signal "L09_GND4")
		(2 "B.Cu" signal "BOTTOM")
		(9 "F.Adhes" user "F.Adhesive")
		(11 "B.Adhes" user "B.Adhesive")
		(13 "F.Paste" user "Package Geometry/Pastemask Top")
		(15 "B.Paste" user "Package Geometry/Pastemask Bottom")
		(5 "F.SilkS" user "Ref Des/Silkscreen Top")
		(7 "B.SilkS" user "Ref Des/Silkscreen Bottom")
		(1 "F.Mask" user "Board Geometry/Soldermask Top")
		(3 "B.Mask" user "Board Geometry/Soldermask Bottom")
		(17 "Dwgs.User" user "User.Drawings")
		(19 "Cmts.User" user "User.Comments")
		(21 "Eco1.User" user "User.Eco1")
		(23 "Eco2.User" user "User.Eco2")
		(25 "Edge.Cuts" user "Board Geometry/Outline")
		(27 "Margin" user)
		(31 "F.CrtYd" user "Package Geometry/Place Bound Top")
		(29 "B.CrtYd" user "Package Geometry/Place Bound Bottom")
		(35 "F.Fab" user "Ref Des/Assembly Top")
		(33 "B.Fab" user "Ref Des/Assembly Bottom")
	)
	(footprint ""
		(layer "F.Cu")
		(at 161.04997 -89.149936 -90)
		(property "Reference" "P3"
			(at -8.232394 -0.36703 0)
			(unlocked yes)
			(layer "F.SilkS")
			(effects
				(font
					(size 0.7874 0.5842)
					(thickness 0.1524)
				)
			)
		)
		(property "Value" ""
			(at 0 0 270)
			(layer "F.Fab")
			(effects
				(font
					(size 1.27 1.27)
				)
			)
		)
		(property "Device Type" "CONN_HDR_2X3_M_RA_TH-G200-1251A"
			(at 0 14.183868 270)
			(unlocked yes)
			(layer "F.Fab")
			(hide yes)
			(effects
				(font
					(size 0.7874 0.5842)
					(thickness 0.1524)
				)
			)
		)
		(property "User Part Number" "PARTNUM*"
			(at 0 15.377668 270)
			(unlocked yes)
			(layer "Cmts.User")
			(hide yes)
			(effects
				(font
					(size 0.7874 0.5842)
					(thickness 0.1524)
				)
			)
		)
		(duplicate_pad_numbers_are_jumpers no)
		(fp_line
			(start -7.343902 13.074904)
			(end -7.343902 -7.043928)
			(stroke
				(width 0.1)
				(type default)
			)
			(layer "F.SilkS")
		)
		(fp_line
			(start 7.343902 13.074904)
			(end -7.343902 13.074904)
			(stroke
				(width 0.1)
				(type default)
			)
			(layer "F.SilkS")
		)
		(fp_line
			(start -7.343902 -7.043928)
			(end 7.343902 -7.043928)
			(stroke
				(width 0.1)
				(type default)
			)
			(layer "F.SilkS")
		)
		(fp_line
			(start 7.343902 -7.043928)
			(end 7.343902 13.074904)
			(stroke
				(width 0.1)
				(type default)
			)
			(layer "F.SilkS")
		)
		(fp_rect
			(start 10.60069 17.900904)
			(end -10.60069 0.89916)
			(stroke
				(width 0)
				(type default)
			)
			(fill no)
			(layer "B.CrtYd")
		)
		(fp_rect
			(start 7.597902 13.328904)
			(end -7.597902 -7.297928)
			(stroke
				(width 0)
				(type default)
			)
			(fill no)
			(layer "F.CrtYd")
		)
		(fp_line
			(start -7.089902 6.389878)
			(end -7.089902 -6.789928)
			(stroke
				(width 0.1)
				(type default)
			)
			(layer "F.Fab")
		)
		(fp_line
			(start 7.089902 6.389878)
			(end -7.089902 6.389878)
			(stroke
				(width 0.1)
				(type default)
			)
			(layer "F.Fab")
		)
		(fp_line
			(start -7.089902 -6.789928)
			(end 7.089902 -6.789928)
			(stroke
				(width 0.1)
				(type default)
			)
			(layer "F.Fab")
		)
		(fp_line
			(start 7.089902 -6.789928)
			(end 7.089902 6.389878)
			(stroke
				(width 0.1)
				(type default)
			)
			(layer "F.Fab")
		)
		(fp_text user "4"
			(at -8.092694 11.06297 0)
			(unlocked yes)
			(layer "F.SilkS")
			(effects
				(font
					(size 0.7874 0.5842)
					(thickness 0.1524)
				)
			)
		)
		(fp_text user "6"
			(at 8.163306 9.53897 0)
			(unlocked yes)
			(layer "F.SilkS")
			(effects
				(font
					(size 0.7874 0.5842)
					(thickness 0.1524)
				)
			)
		)
		(fp_text user "1"
			(at -7.965694 6.49097 0)
			(unlocked yes)
			(layer "F.SilkS")
			(effects
				(font
					(size 0.7874 0.5842)
					(thickness 0.1524)
				)
			)
		)
		(fp_text user "3"
			(at 8.036306 5.98297 0)
			(unlocked yes)
			(layer "F.SilkS")
			(effects
				(font
					(size 0.7874 0.5842)
					(thickness 0.1524)
				)
			)
		)
		(fp_text user "6"
			(at 6.996176 11.553444 0)
			(unlocked yes)
			(layer "F.Fab")
			(effects
				(font
					(size 0.7874 0.5842)
					(thickness 0.1524)
				)
			)
		)
		(fp_text user "4"
			(at -7.671308 11.30173 0)
			(unlocked yes)
			(layer "F.Fab")
			(effects
				(font
					(size 0.7874 0.5842)
					(thickness 0.1524)
				)
			)
		)
		(fp_text user "3"
			(at 7.120636 7.170674 0)
			(unlocked yes)
			(layer "F.Fab")
			(effects
				(font
					(size 0.7874 0.5842)
					(thickness 0.1524)
				)
			)
		)
		(fp_text user "1"
			(at -7.515606 6.825742 0)
			(unlocked yes)
			(layer "F.Fab")
			(effects
				(font
					(size 0.7874 0.5842)
					(thickness 0.1524)
				)
			)
		)
		(pad "" np_thru_hole circle
			(at -4.19989 0 270)
			(size 2.7432 2.7432)
			(drill 2.9972)
			(layers "*.Cu" "*.Mask")
			(padstack
				(mode front_inner_back)
				(layer "Inner"
					(shape circle)
					(size 2.7432 2.7432)
					(clearance 0.4445)
				)
				(layer "B.Cu"
					(shape circle)
					(size 2.7432 2.7432)
				)
			)
		)
		(pad "" np_thru_hole circle
			(at 4.19989 0 270)
			(size 2.7432 2.7432)
			(drill 2.9972)
			(layers "*.Cu" "*.Mask")
			(padstack
				(mode front_inner_back)
				(layer "Inner"
					(shape circle)
					(size 2.7432 2.7432)
					(clearance 0.4445)
				)
				(layer "B.Cu"
					(shape circle)
					(size 2.7432 2.7432)
				)
			)
		)
		(pad "1" thru_hole rect
			(at -4.19989 7.29996 270)
			(size 2.6416 2.6416)
			(drill 1.9304)
			(layers "*.Cu" "*.Mask")
			(remove_unused_layers no)
			(net "XP12R0V_EXT")
			(padstack
				(mode front_inner_back)
				(layer "Inner"
					(shape circle)
					(size 2.6416 2.6416)
					(clearance -0.0635)
				)
				(layer "B.Cu"
					(shape rect)
					(size 2.6416 2.6416)
				)
			)
		)
		(pad "2" thru_hole circle
			(at 0 7.29996 270)
			(size 2.6416 2.6416)
			(drill 1.9304)
			(layers "*.Cu" "*.Mask")
			(remove_unused_layers no)
			(net "XP12R0V_EXT")
			(padstack
				(mode front_inner_back)
				(layer "Inner"
					(shape circle)
					(size 2.6416 2.6416)
					(clearance -0.0635)
				)
				(layer "B.Cu"
					(shape circle)
					(size 2.6416 2.6416)
				)
			)
		)
		(pad "3" thru_hole circle
			(at 4.19989 7.29996 270)
			(size 2.6416 2.6416)
			(drill 1.9304)
			(layers "*.Cu" "*.Mask")
			(remove_unused_layers no)
			(net "XP12R0V_EXT")
			(padstack
				(mode front_inner_back)
				(layer "Inner"
					(shape circle)
					(size 2.6416 2.6416)
					(clearance -0.0635)
				)
				(layer "B.Cu"
					(shape circle)
					(size 2.6416 2.6416)
				)
			)
		)
		(pad "4" thru_hole circle
			(at -4.19989 11.500104 270)
			(size 2.6416 2.6416)
			(drill 1.9304)
			(layers "*.Cu" "*.Mask")
			(remove_unused_layers no)
			(net "SG")
			(padstack
				(mode front_inner_back)
				(layer "Inner"
					(shape circle)
					(size 2.6416 2.6416)
					(clearance -0.0635)
				)
				(layer "B.Cu"
					(shape circle)
					(size 2.6416 2.6416)
				)
			)
		)
		(pad "5" thru_hole circle
			(at 0 11.500104 270)
			(size 2.6416 2.6416)
			(drill 1.9304)
			(layers "*.Cu" "*.Mask")
			(remove_unused_layers no)
			(net "SG")
			(padstack
				(mode front_inner_back)
				(layer "Inner"
					(shape circle)
					(size 2.6416 2.6416)
					(clearance -0.0635)
				)
				(layer "B.Cu"
					(shape circle)
					(size 2.6416 2.6416)
				)
			)
		)
		(pad "6" thru_hole circle
			(at 4.19989 11.500104 270)
			(size 2.6416 2.6416)
			(drill 1.9304)
			(layers "*.Cu" "*.Mask")
			(remove_unused_layers no)
			(net "SG")
			(padstack
				(mode front_inner_back)
				(layer "Inner"
					(shape circle)
					(size 2.6416 2.6416)
					(clearance -0.0635)
				)
				(layer "B.Cu"
					(shape circle)
					(size 2.6416 2.6416)
				)
			)
		)
		(zone
			(layers "F.Cu" "B.Cu" "In1.Cu" "In2.Cu" "In3.Cu" "In4.Cu" "In5.Cu" "In6.Cu"
				"In7.Cu" "In8.Cu"
			)
			(hatch none 0.5)
			(connect_pads
				(clearance 0)
			)
			(min_thickness 0.25)
			(keepout
				(tracks not_allowed)
				(vias allowed)
				(pads allowed)
				(copperpour not_allowed)
				(footprints allowed)
			)
			(placement
				(enabled no)
				(sheetname "")
			)
			(fill
				(thermal_gap 0.5)
				(thermal_bridge_width 0.5)
				(island_removal_mode 0)
			)
			(polygon
				(pts
					(arc
						(start 163.18357 -93.349826)
						(mid 158.91637 -93.349826)
						(end 163.18357 -93.349826)
					)
				)
			)
		)
		(zone
			(layers "F.Cu" "B.Cu" "In1.Cu" "In2.Cu" "In3.Cu" "In4.Cu" "In5.Cu" "In6.Cu"
				"In7.Cu" "In8.Cu"
			)
			(hatch none 0.5)
			(connect_pads
				(clearance 0)
			)
			(min_thickness 0.25)
			(keepout
				(tracks not_allowed)
				(vias allowed)
				(pads allowed)
				(copperpour not_allowed)
				(footprints allowed)
			)
			(placement
				(enabled no)
				(sheetname "")
			)
			(fill
				(thermal_gap 0.5)
				(thermal_bridge_width 0.5)
				(island_removal_mode 0)
			)
			(polygon
				(pts
					(arc
						(start 163.18357 -84.950046)
						(mid 158.91637 -84.950046)
						(end 163.18357 -84.950046)
					)
				)
			)
		)
	)
)
